(kicad_pcb
	(version 20260206)
	(generator "pcbnew")
	(generator_version "10.0")
	(general
		(thickness 1.6)
		(legacy_teardrops no)
	)
	(paper "A4")
	(title_block
		(title "01162023_DA0F0TEBIF0_F0T_Expander_BD_F_brd_V02_OCP.brd")
		(comment 1 "Grand Teton / footprints 9714-9721 of 9728")
	)
	(layers
		(0 "F.Cu" signal "TOP")
		(4 "In1.Cu" signal "GND")
		(6 "In2.Cu" signal "VCC")
		(8 "In3.Cu" signal "VCC1")
		(10 "In4.Cu" signal "GND1")
		(12 "In5.Cu" signal "IN1")
		(14 "In6.Cu" signal "GND2")
		(16 "In7.Cu" signal "IN2")
		(18 "In8.Cu" signal "GND3")
		(20 "In9.Cu" signal "IN3")
		(22 "In10.Cu" signal "GND4")
		(24 "In11.Cu" signal "IN4")
		(26 "In12.Cu" signal "GND5")
		(28 "In13.Cu" signal "IN5")
		(30 "In14.Cu" signal "GND6")
		(32 "In15.Cu" signal "IN6")
		(34 "In16.Cu" signal "GND7")
		(2 "B.Cu" signal "BOTTOM")
		(9 "F.Adhes" user "F.Adhesive")
		(11 "B.Adhes" user "B.Adhesive")
		(13 "F.Paste" user "Package Geometry/Pastemask Top")
		(15 "B.Paste" user "Package Geometry/Pastemask Bottom")
		(5 "F.SilkS" user "Ref Des/Silkscreen Top")
		(7 "B.SilkS" user "Ref Des/Silkscreen Bottom")
		(1 "F.Mask" user "Board Geometry/Soldermask Top")
		(3 "B.Mask" user "Board Geometry/Soldermask Bottom")
		(17 "Dwgs.User" user "User.Drawings")
		(19 "Cmts.User" user "User.Comments")
		(21 "Eco1.User" user "User.Eco1")
		(23 "Eco2.User" user "User.Eco2")
		(25 "Edge.Cuts" user "Board Geometry/Outline")
		(27 "Margin" user)
		(31 "F.CrtYd" user "Package Geometry/Place Bound Top")
		(29 "B.CrtYd" user "Package Geometry/Place Bound Bottom")
		(35 "F.Fab" user "Ref Des/Assembly Top")
		(33 "B.Fab" user "Ref Des/Assembly Bottom")
	)
	(footprint ""
		(layer "B.Cu")
		(at 228.531928 -286.538162 180)
		(property "Reference" "PC235"
			(at 0 0 0)
			(layer "B.SilkS")
			(hide yes)
			(effects
				(font
					(size 1.27 1.27)
				)
				(justify mirror)
			)
		)
		(property "Value" ""
			(at 0 0 0)
			(layer "B.Fab")
			(effects
				(font
					(size 1.27 1.27)
				)
				(justify mirror)
			)
		)
		(duplicate_pad_numbers_are_jumpers no)
		(fp_line
			(start 1.524 0.762)
			(end 1.524 -0.762)
			(stroke
				(width 0.1524)
				(type default)
			)
			(layer "B.SilkS")
		)
		(fp_line
			(start 1.524 -0.762)
			(end -1.524 -0.762)
			(stroke
				(width 0.1524)
				(type default)
			)
			(layer "B.SilkS")
		)
		(fp_line
			(start -1.524 0.762)
			(end 1.524 0.762)
			(stroke
				(width 0.1524)
				(type default)
			)
			(layer "B.SilkS")
		)
		(fp_line
			(start -1.524 -0.762)
			(end -1.524 0.762)
			(stroke
				(width 0.1524)
				(type default)
			)
			(layer "B.SilkS")
		)
		(fp_line
			(start 1.1049 0.724916)
			(end -1.1049 0.724916)
			(stroke
				(width 0.1)
				(type default)
			)
			(layer "B.Fab")
		)
		(fp_line
			(start 1.1049 -0.724916)
			(end 1.1049 0.724916)
			(stroke
				(width 0.1)
				(type default)
			)
			(layer "B.Fab")
		)
		(fp_line
			(start -1.1049 0.724916)
			(end -1.1049 -0.724916)
			(stroke
				(width 0.1)
				(type default)
			)
			(layer "B.Fab")
		)
		(fp_line
			(start -1.1049 -0.724916)
			(end 1.1049 -0.724916)
			(stroke
				(width 0.1)
				(type default)
			)
			(layer "B.Fab")
		)
		(pad "1" smd rect
			(at 0.889 0 180)
			(size 1.016 1.27)
			(layers "B.Cu" "B.Mask" "B.Paste")
			(net "P1V25_PEX1_R")
		)
		(pad "2" smd rect
			(at -0.889 0 180)
			(size 1.016 1.27)
			(layers "B.Cu" "B.Mask" "B.Paste")
			(net "GND")
		)
	)
	(footprint ""
		(layer "B.Cu")
		(at 302.877474 -221.694502 90)
		(property "Reference" "R1867"
			(at 0 0 90)
			(layer "B.SilkS")
			(hide yes)
			(effects
				(font
					(size 1.27 1.27)
				)
				(justify mirror)
			)
		)
		(property "Value" ""
			(at 0 0 90)
			(layer "B.Fab")
			(effects
				(font
					(size 1.27 1.27)
				)
				(justify mirror)
			)
		)
		(duplicate_pad_numbers_are_jumpers no)
		(fp_line
			(start 0.7874 -0.4064)
			(end -0.7874 -0.4064)
			(stroke
				(width 0.1524)
				(type default)
			)
			(layer "B.SilkS")
		)
		(fp_line
			(start -0.7874 -0.4064)
			(end -0.7874 0.4064)
			(stroke
				(width 0.1524)
				(type default)
			)
			(layer "B.SilkS")
		)
		(fp_line
			(start 0.7874 0.4064)
			(end 0.7874 -0.4064)
			(stroke
				(width 0.1524)
				(type default)
			)
			(layer "B.SilkS")
		)
		(fp_line
			(start -0.7874 0.4064)
			(end 0.7874 0.4064)
			(stroke
				(width 0.1524)
				(type default)
			)
			(layer "B.SilkS")
		)
		(fp_line
			(start 0.67945 -0.305054)
			(end 0.12065 -0.305054)
			(stroke
				(width 0.1)
				(type default)
			)
			(layer "B.Fab")
		)
		(fp_line
			(start 0.12065 -0.305054)
			(end 0.12065 -0.2794)
			(stroke
				(width 0.1)
				(type default)
			)
			(layer "B.Fab")
		)
		(fp_line
			(start -0.12065 -0.3048)
			(end -0.67945 -0.3048)
			(stroke
				(width 0.1)
				(type default)
			)
			(layer "B.Fab")
		)
		(fp_line
			(start -0.67945 -0.3048)
			(end -0.67945 0.3048)
			(stroke
				(width 0.1)
				(type default)
			)
			(layer "B.Fab")
		)
		(fp_line
			(start 0.12065 -0.2794)
			(end -0.12065 -0.2794)
			(stroke
				(width 0.1)
				(type default)
			)
			(layer "B.Fab")
		)
		(fp_line
			(start -0.12065 -0.2794)
			(end -0.12065 -0.3048)
			(stroke
				(width 0.1)
				(type default)
			)
			(layer "B.Fab")
		)
		(fp_line
			(start 0.12065 0.2794)
			(end 0.12065 0.3048)
			(stroke
				(width 0.1)
				(type default)
			)
			(layer "B.Fab")
		)
		(fp_line
			(start -0.120396 0.2794)
			(end 0.12065 0.2794)
			(stroke
				(width 0.1)
				(type default)
			)
			(layer "B.Fab")
		)
		(fp_line
			(start 0.67945 0.3048)
			(end 0.67945 -0.305054)
			(stroke
				(width 0.1)
				(type default)
			)
			(layer "B.Fab")
		)
		(fp_line
			(start 0.12065 0.3048)
			(end 0.67945 0.3048)
			(stroke
				(width 0.1)
				(type default)
			)
			(layer "B.Fab")
		)
		(fp_line
			(start -0.120396 0.3048)
			(end -0.120396 0.2794)
			(stroke
				(width 0.1)
				(type default)
			)
			(layer "B.Fab")
		)
		(fp_line
			(start -0.67945 0.3048)
			(end -0.120396 0.3048)
			(stroke
				(width 0.1)
				(type default)
			)
			(layer "B.Fab")
		)
		(pad "1" smd circle
			(at 0.40005 0 270)
			(size 0 0)
			(layers "B.Cu" "B.Mask" "B.Paste")
			(net "RST_GPU_PERST_1_BUF_N")
		)
		(pad "2" smd circle
			(at -0.40005 0 270)
			(size 0 0)
			(layers "B.Cu" "B.Mask" "B.Paste")
			(net "RST_GPU_PERST_1_BUF_R_N")
		)
	)
	(footprint ""
		(layer "B.Cu")
		(at 77.541882 -97.005648 180)
		(property "Reference" "R63"
			(at 0 0 0)
			(layer "B.SilkS")
			(hide yes)
			(effects
				(font
					(size 1.27 1.27)
				)
				(justify mirror)
			)
		)
		(property "Value" ""
			(at 0 0 0)
			(layer "B.Fab")
			(effects
				(font
					(size 1.27 1.27)
				)
				(justify mirror)
			)
		)
		(duplicate_pad_numbers_are_jumpers no)
		(fp_line
			(start 0.7874 0.4064)
			(end 0.7874 -0.4064)
			(stroke
				(width 0.1524)
				(type default)
			)
			(layer "B.SilkS")
		)
		(fp_line
			(start 0.7874 -0.4064)
			(end -0.7874 -0.4064)
			(stroke
				(width 0.1524)
				(type default)
			)
			(layer "B.SilkS")
		)
		(fp_line
			(start -0.7874 0.4064)
			(end 0.7874 0.4064)
			(stroke
				(width 0.1524)
				(type default)
			)
			(layer "B.SilkS")
		)
		(fp_line
			(start -0.7874 -0.4064)
			(end -0.7874 0.4064)
			(stroke
				(width 0.1524)
				(type default)
			)
			(layer "B.SilkS")
		)
		(fp_line
			(start 0.67945 0.3048)
			(end 0.67945 -0.305054)
			(stroke
				(width 0.1)
				(type default)
			)
			(layer "B.Fab")
		)
		(fp_line
			(start 0.67945 -0.305054)
			(end 0.12065 -0.305054)
			(stroke
				(width 0.1)
				(type default)
			)
			(layer "B.Fab")
		)
		(fp_line
			(start 0.12065 0.3048)
			(end 0.67945 0.3048)
			(stroke
				(width 0.1)
				(type default)
			)
			(layer "B.Fab")
		)
		(fp_line
			(start 0.12065 0.2794)
			(end 0.12065 0.3048)
			(stroke
				(width 0.1)
				(type default)
			)
			(layer "B.Fab")
		)
		(fp_line
			(start 0.12065 -0.2794)
			(end -0.12065 -0.2794)
			(stroke
				(width 0.1)
				(type default)
			)
			(layer "B.Fab")
		)
		(fp_line
			(start 0.12065 -0.305054)
			(end 0.12065 -0.2794)
			(stroke
				(width 0.1)
				(type default)
			)
			(layer "B.Fab")
		)
		(fp_line
			(start -0.120396 0.3048)
			(end -0.120396 0.2794)
			(stroke
				(width 0.1)
				(type default)
			)
			(layer "B.Fab")
		)
		(fp_line
			(start -0.120396 0.2794)
			(end 0.12065 0.2794)
			(stroke
				(width 0.1)
				(type default)
			)
			(layer "B.Fab")
		)
		(fp_line
			(start -0.12065 -0.2794)
			(end -0.12065 -0.3048)
			(stroke
				(width 0.1)
				(type default)
			)
			(layer "B.Fab")
		)
		(fp_line
			(start -0.12065 -0.3048)
			(end -0.67945 -0.3048)
			(stroke
				(width 0.1)
				(type default)
			)
			(layer "B.Fab")
		)
		(fp_line
			(start -0.67945 0.3048)
			(end -0.120396 0.3048)
			(stroke
				(width 0.1)
				(type default)
			)
			(layer "B.Fab")
		)
		(fp_line
			(start -0.67945 -0.3048)
			(end -0.67945 0.3048)
			(stroke
				(width 0.1)
				(type default)
			)
			(layer "B.Fab")
		)
		(pad "1" smd circle
			(at 0.40005 0)
			(size 0 0)
			(layers "B.Cu" "B.Mask" "B.Paste")
			(net "NIC1_DATA_IN")
		)
		(pad "2" smd circle
			(at -0.40005 0)
			(size 0 0)
			(layers "B.Cu" "B.Mask" "B.Paste")
			(net "P3V3_NIC1")
		)
	)
	(footprint ""
		(layer "B.Cu")
		(at 401.299934 -299.699934 -90)
		(property "Reference" "C1994"
			(at 0 0 90)
			(layer "B.SilkS")
			(hide yes)
			(effects
				(font
					(size 1.27 1.27)
				)
				(justify mirror)
			)
		)
		(property "Value" ""
			(at 0 0 90)
			(layer "B.Fab")
			(effects
				(font
					(size 1.27 1.27)
				)
				(justify mirror)
			)
		)
		(duplicate_pad_numbers_are_jumpers no)
		(fp_line
			(start -0.299974 0.150114)
			(end 0.299974 0.150114)
			(stroke
				(width 0.1)
				(type default)
			)
			(layer "B.Fab")
		)
		(fp_line
			(start 0.299974 0.150114)
			(end 0.299974 -0.150114)
			(stroke
				(width 0.1)
				(type default)
			)
			(layer "B.Fab")
		)
		(fp_line
			(start -0.299974 -0.150114)
			(end -0.299974 0.150114)
			(stroke
				(width 0.1)
				(type default)
			)
			(layer "B.Fab")
		)
		(fp_line
			(start 0.299974 -0.150114)
			(end -0.299974 -0.150114)
			(stroke
				(width 0.1)
				(type default)
			)
			(layer "B.Fab")
		)
		(pad "1" smd rect
			(at 0.2667 0 90)
			(size 0.3048 0.381)
			(layers "B.Cu" "B.Mask" "B.Paste")
			(net "P0V8_SERDES_VDDA_PEX3")
		)
		(pad "2" smd rect
			(at -0.2667 0 90)
			(size 0.3048 0.381)
			(layers "B.Cu" "B.Mask" "B.Paste")
			(net "GND")
		)
	)
	(footprint ""
		(layer "B.Cu")
		(at 333.89824 -219.902278 -90)
		(property "Reference" "C2084"
			(at 0 0 90)
			(layer "B.SilkS")
			(hide yes)
			(effects
				(font
					(size 1.27 1.27)
				)
				(justify mirror)
			)
		)
		(property "Value" ""
			(at 0 0 90)
			(layer "B.Fab")
			(effects
				(font
					(size 1.27 1.27)
				)
				(justify mirror)
			)
		)
		(duplicate_pad_numbers_are_jumpers no)
		(fp_line
			(start -0.69215 0.2921)
			(end 0.69215 0.2921)
			(stroke
				(width 0.1524)
				(type default)
			)
			(layer "B.SilkS")
		)
		(fp_line
			(start 0.69215 0.2921)
			(end 0.69215 -0.2921)
			(stroke
				(width 0.1524)
				(type default)
			)
			(layer "B.SilkS")
		)
		(fp_line
			(start -0.69215 -0.2921)
			(end -0.69215 0.2921)
			(stroke
				(width 0.1524)
				(type default)
			)
			(layer "B.SilkS")
		)
		(fp_line
			(start 0.69215 -0.2921)
			(end -0.69215 -0.2921)
			(stroke
				(width 0.1524)
				(type default)
			)
			(layer "B.SilkS")
		)
		(fp_line
			(start -0.51435 0.2794)
			(end 0.51435 0.2794)
			(stroke
				(width 0.1)
				(type default)
			)
			(layer "B.Fab")
		)
		(fp_line
			(start 0.51435 0.2794)
			(end 0.51435 -0.2794)
			(stroke
				(width 0.1)
				(type default)
			)
			(layer "B.Fab")
		)
		(fp_line
			(start -0.51435 -0.2794)
			(end -0.51435 0.2794)
			(stroke
				(width 0.1)
				(type default)
			)
			(layer "B.Fab")
		)
		(fp_line
			(start 0.51435 -0.2794)
			(end -0.51435 -0.2794)
			(stroke
				(width 0.1)
				(type default)
			)
			(layer "B.Fab")
		)
		(pad "1" smd circle
			(at 0.40005 0 90)
			(size 0 0)
			(layers "B.Cu" "B.Mask" "B.Paste")
			(net "P3V3_FPGA_VCCIO4")
		)
		(pad "2" smd circle
			(at -0.40005 0 90)
			(size 0 0)
			(layers "B.Cu" "B.Mask" "B.Paste")
			(net "GND")
		)
		(zone
			(layer "B.Cu")
			(hatch none 0.5)
			(connect_pads
				(clearance 0)
			)
			(min_thickness 0.25)
			(keepout
				(tracks not_allowed)
				(vias allowed)
				(pads allowed)
				(copperpour not_allowed)
				(footprints allowed)
			)
			(placement
				(enabled no)
				(sheetname "")
			)
			(fill
				(thermal_gap 0.5)
				(thermal_bridge_width 0.5)
				(island_removal_mode 0)
			)
			(polygon
				(pts
					(xy 333.81061 -219.711778) (xy 333.752444 -219.803218) (xy 333.752444 -220.002608) (xy 333.81061 -220.092778)
					(xy 333.98587 -220.092778) (xy 334.04429 -220.002608) (xy 334.04429 -219.803218) (xy 333.986124 -219.711778)
				)
			)
		)
	)
	(footprint ""
		(layer "B.Cu")
		(at 213.801198 -219.306902)
		(property "Reference" "R4887"
			(at 0 0 0)
			(layer "B.SilkS")
			(hide yes)
			(effects
				(font
					(size 1.27 1.27)
				)
				(justify mirror)
			)
		)
		(property "Value" ""
			(at 0 0 0)
			(layer "B.Fab")
			(effects
				(font
					(size 1.27 1.27)
				)
				(justify mirror)
			)
		)
		(duplicate_pad_numbers_are_jumpers no)
		(fp_line
			(start -0.7874 -0.4064)
			(end -0.7874 0.4064)
			(stroke
				(width 0.1524)
				(type default)
			)
			(layer "B.SilkS")
		)
		(fp_line
			(start -0.7874 0.4064)
			(end 0.7874 0.4064)
			(stroke
				(width 0.1524)
				(type default)
			)
			(layer "B.SilkS")
		)
		(fp_line
			(start 0.7874 -0.4064)
			(end -0.7874 -0.4064)
			(stroke
				(width 0.1524)
				(type default)
			)
			(layer "B.SilkS")
		)
		(fp_line
			(start 0.7874 0.4064)
			(end 0.7874 -0.4064)
			(stroke
				(width 0.1524)
				(type default)
			)
			(layer "B.SilkS")
		)
		(fp_line
			(start -0.67945 -0.3048)
			(end -0.67945 0.3048)
			(stroke
				(width 0.1)
				(type default)
			)
			(layer "B.Fab")
		)
		(fp_line
			(start -0.67945 0.3048)
			(end -0.120396 0.3048)
			(stroke
				(width 0.1)
				(type default)
			)
			(layer "B.Fab")
		)
		(fp_line
			(start -0.12065 -0.3048)
			(end -0.67945 -0.3048)
			(stroke
				(width 0.1)
				(type default)
			)
			(layer "B.Fab")
		)
		(fp_line
			(start -0.12065 -0.2794)
			(end -0.12065 -0.3048)
			(stroke
				(width 0.1)
				(type default)
			)
			(layer "B.Fab")
		)
		(fp_line
			(start -0.120396 0.2794)
			(end 0.12065 0.2794)
			(stroke
				(width 0.1)
				(type default)
			)
			(layer "B.Fab")
		)
		(fp_line
			(start -0.120396 0.3048)
			(end -0.120396 0.2794)
			(stroke
				(width 0.1)
				(type default)
			)
			(layer "B.Fab")
		)
		(fp_line
			(start 0.12065 -0.305054)
			(end 0.12065 -0.2794)
			(stroke
				(width 0.1)
				(type default)
			)
			(layer "B.Fab")
		)
		(fp_line
			(start 0.12065 -0.2794)
			(end -0.12065 -0.2794)
			(stroke
				(width 0.1)
				(type default)
			)
			(layer "B.Fab")
		)
		(fp_line
			(start 0.12065 0.2794)
			(end 0.12065 0.3048)
			(stroke
				(width 0.1)
				(type default)
			)
			(layer "B.Fab")
		)
		(fp_line
			(start 0.12065 0.3048)
			(end 0.67945 0.3048)
			(stroke
				(width 0.1)
				(type default)
			)
			(layer "B.Fab")
		)
		(fp_line
			(start 0.67945 -0.305054)
			(end 0.12065 -0.305054)
			(stroke
				(width 0.1)
				(type default)
			)
			(layer "B.Fab")
		)
		(fp_line
			(start 0.67945 0.3048)
			(end 0.67945 -0.305054)
			(stroke
				(width 0.1)
				(type default)
			)
			(layer "B.Fab")
		)
		(pad "1" smd circle
			(at 0.40005 0 180)
			(size 0 0)
			(layers "B.Cu" "B.Mask" "B.Paste")
			(net "SMB_PEX_R_SCL")
		)
		(pad "2" smd circle
			(at -0.40005 0 180)
			(size 0 0)
			(layers "B.Cu" "B.Mask" "B.Paste")
			(net "P3V3_AUX")
		)
	)
	(footprint ""
		(layer "B.Cu")
		(at 49.5554 -156.0576)
		(property "Reference" "R28"
			(at 0 0 0)
			(layer "B.SilkS")
			(hide yes)
			(effects
				(font
					(size 1.27 1.27)
				)
				(justify mirror)
			)
		)
		(property "Value" ""
			(at 0 0 0)
			(layer "B.Fab")
			(effects
				(font
					(size 1.27 1.27)
				)
				(justify mirror)
			)
		)
		(duplicate_pad_numbers_are_jumpers no)
		(fp_line
			(start -0.7874 -0.4064)
			(end -0.7874 0.4064)
			(stroke
				(width 0.1524)
				(type default)
			)
			(layer "B.SilkS")
		)
		(fp_line
			(start -0.7874 0.4064)
			(end 0.7874 0.4064)
			(stroke
				(width 0.1524)
				(type default)
			)
			(layer "B.SilkS")
		)
		(fp_line
			(start 0.7874 -0.4064)
			(end -0.7874 -0.4064)
			(stroke
				(width 0.1524)
				(type default)
			)
			(layer "B.SilkS")
		)
		(fp_line
			(start 0.7874 0.4064)
			(end 0.7874 -0.4064)
			(stroke
				(width 0.1524)
				(type default)
			)
			(layer "B.SilkS")
		)
		(fp_line
			(start -0.67945 -0.3048)
			(end -0.67945 0.3048)
			(stroke
				(width 0.1)
				(type default)
			)
			(layer "B.Fab")
		)
		(fp_line
			(start -0.67945 0.3048)
			(end -0.120396 0.3048)
			(stroke
				(width 0.1)
				(type default)
			)
			(layer "B.Fab")
		)
		(fp_line
			(start -0.12065 -0.3048)
			(end -0.67945 -0.3048)
			(stroke
				(width 0.1)
				(type default)
			)
			(layer "B.Fab")
		)
		(fp_line
			(start -0.12065 -0.2794)
			(end -0.12065 -0.3048)
			(stroke
				(width 0.1)
				(type default)
			)
			(layer "B.Fab")
		)
		(fp_line
			(start -0.120396 0.2794)
			(end 0.12065 0.2794)
			(stroke
				(width 0.1)
				(type default)
			)
			(layer "B.Fab")
		)
		(fp_line
			(start -0.120396 0.3048)
			(end -0.120396 0.2794)
			(stroke
				(width 0.1)
				(type default)
			)
			(layer "B.Fab")
		)
		(fp_line
			(start 0.12065 -0.305054)
			(end 0.12065 -0.2794)
			(stroke
				(width 0.1)
				(type default)
			)
			(layer "B.Fab")
		)
		(fp_line
			(start 0.12065 -0.2794)
			(end -0.12065 -0.2794)
			(stroke
				(width 0.1)
				(type default)
			)
			(layer "B.Fab")
		)
		(fp_line
			(start 0.12065 0.2794)
			(end 0.12065 0.3048)
			(stroke
				(width 0.1)
				(type default)
			)
			(layer "B.Fab")
		)
		(fp_line
			(start 0.12065 0.3048)
			(end 0.67945 0.3048)
			(stroke
				(width 0.1)
				(type default)
			)
			(layer "B.Fab")
		)
		(fp_line
			(start 0.67945 -0.305054)
			(end 0.12065 -0.305054)
			(stroke
				(width 0.1)
				(type default)
			)
			(layer "B.Fab")
		)
		(fp_line
			(start 0.67945 0.3048)
			(end 0.67945 -0.305054)
			(stroke
				(width 0.1)
				(type default)
			)
			(layer "B.Fab")
		)
		(pad "1" smd circle
			(at 0.40005 0 180)
			(size 0 0)
			(layers "B.Cu" "B.Mask" "B.Paste")
			(net "NIC0_SLOT_ID1")
		)
		(pad "2" smd circle
			(at -0.40005 0 180)
			(size 0 0)
			(layers "B.Cu" "B.Mask" "B.Paste")
			(net "GND")
		)
	)
	(footprint ""
		(layer "B.Cu")
		(at 394.65504 -296.37482)
		(property "Reference" "C3551"
			(at 0 0 0)
			(layer "B.SilkS")
			(hide yes)
			(effects
				(font
					(size 1.27 1.27)
				)
				(justify mirror)
			)
		)
		(property "Value" ""
			(at 0 0 0)
			(layer "B.Fab")
			(effects
				(font
					(size 1.27 1.27)
				)
				(justify mirror)
			)
		)
		(duplicate_pad_numbers_are_jumpers no)
		(fp_line
			(start -0.299974 -0.150114)
			(end -0.299974 0.150114)
			(stroke
				(width 0.1)
				(type default)
			)
			(layer "B.Fab")
		)
		(fp_line
			(start -0.299974 0.150114)
			(end 0.299974 0.150114)
			(stroke
				(width 0.1)
				(type default)
			)
			(layer "B.Fab")
		)
		(fp_line
			(start 0.299974 -0.150114)
			(end -0.299974 -0.150114)
			(stroke
				(width 0.1)
				(type default)
			)
			(layer "B.Fab")
		)
		(fp_line
			(start 0.299974 0.150114)
			(end 0.299974 -0.150114)
			(stroke
				(width 0.1)
				(type default)
			)
			(layer "B.Fab")
		)
		(pad "1" smd rect
			(at 0.2667 0 180)
			(size 0.3048 0.381)
			(layers "B.Cu" "B.Mask" "B.Paste")
			(net "PCEPLL2_VDDA18_PEX3")
		)
		(pad "2" smd rect
			(at -0.2667 0 180)
			(size 0.3048 0.381)
			(layers "B.Cu" "B.Mask" "B.Paste")
			(net "GND")
		)
	)
)
